# S9S_MB_2U (Grand Teton) — schematic netlist excerpt (pin names and nets, part order shuffled) for the footprints in the layout excerpt that follows; sources: Cadence DE-HDL packaged netlist, KiCad conversion of 03242023_DA0F0TMBIJ0_F0T_Motherboard_J_brd_V01_OCP.brd

C1842  Q_CAP  10UF 6.3V 20% X6S  pkg C0402  page 217 : A = P3V3_AUX_FPGA_VCCIO3 ; B = GND
C205  Q_CAP  0.1UF 25V 10% X7R  pkg 0402  page 206 : A = P3V3_DB2000_VDD ; B = GND

(kicad_pcb
	(version 20260206)
	(generator "pcbnew")
	(generator_version "10.0")
	(general
		(thickness 1.6)
		(legacy_teardrops no)
	)
	(paper "A4")
	(title_block
		(title "03242023_DA0F0TMBIJ0_F0T_Motherboard_J_brd_V01_OCP.brd")
		(comment 1 "Grand Teton / footprints 5046-5047 of 6105")
	)
	(layers
		(0 "F.Cu" signal "TOP")
		(4 "In1.Cu" signal "GND")
		(6 "In2.Cu" signal "IN1")
		(8 "In3.Cu" signal "GND1")
		(10 "In4.Cu" signal "IN2")
		(12 "In5.Cu" signal "GND2")
		(14 "In6.Cu" signal "IN3")
		(16 "In7.Cu" signal "GND3")
		(18 "In8.Cu" signal "VCC")
		(20 "In9.Cu" signal "VCC1")
		(22 "In10.Cu" signal "GND4")
		(24 "In11.Cu" signal "IN4")
		(26 "In12.Cu" signal "GND5")
		(28 "In13.Cu" signal "IN5")
		(30 "In14.Cu" signal "GND6")
		(32 "In15.Cu" signal "IN6")
		(34 "In16.Cu" signal "GND7")
		(2 "B.Cu" signal "BOTTOM")
		(9 "F.Adhes" user "F.Adhesive")
		(11 "B.Adhes" user "B.Adhesive")
		(13 "F.Paste" user "Package Geometry/Pastemask Top")
		(15 "B.Paste" user "Package Geometry/Pastemask Bottom")
		(5 "F.SilkS" user "Ref Des/Silkscreen Top")
		(7 "B.SilkS" user "Ref Des/Silkscreen Bottom")
		(1 "F.Mask" user "Board Geometry/Soldermask Top")
		(3 "B.Mask" user "Board Geometry/Soldermask Bottom")
		(17 "Dwgs.User" user "User.Drawings")
		(19 "Cmts.User" user "User.Comments")
		(21 "Eco1.User" user "User.Eco1")
		(23 "Eco2.User" user "User.Eco2")
		(25 "Edge.Cuts" user "Board Geometry/Outline")
		(27 "Margin" user)
		(31 "F.CrtYd" user "Package Geometry/Place Bound Top")
		(29 "B.CrtYd" user "Package Geometry/Place Bound Bottom")
		(35 "F.Fab" user "Ref Des/Assembly Top")
		(33 "B.Fab" user "Ref Des/Assembly Bottom")
	)
	(footprint ""
		(layer "B.Cu")
		(at 182.68188 -103.723948)
		(property "Reference" "C1842"
			(at 0 0 0)
			(layer "B.SilkS")
			(hide yes)
			(effects
				(font
					(size 1.27 1.27)
				)
				(justify mirror)
			)
		)
		(property "Value" ""
			(at 0 0 0)
			(layer "B.Fab")
			(effects
				(font
					(size 1.27 1.27)
				)
				(justify mirror)
			)
		)
		(duplicate_pad_numbers_are_jumpers no)
		(fp_line
			(start -0.7874 -0.4064)
			(end -0.7874 0.4064)
			(stroke
				(width 0.1524)
				(type default)
			)
			(layer "B.SilkS")
		)
		(fp_line
			(start -0.7874 0.4064)
			(end 0.7874 0.4064)
			(stroke
				(width 0.1524)
				(type default)
			)
			(layer "B.SilkS")
		)
		(fp_line
			(start 0.7874 -0.4064)
			(end -0.7874 -0.4064)
			(stroke
				(width 0.1524)
				(type default)
			)
			(layer "B.SilkS")
		)
		(fp_line
			(start 0.7874 0.4064)
			(end 0.7874 -0.4064)
			(stroke
				(width 0.1524)
				(type default)
			)
			(layer "B.SilkS")
		)
		(fp_line
			(start -0.67945 -0.3048)
			(end -0.67945 0.3048)
			(stroke
				(width 0.1)
				(type default)
			)
			(layer "B.Fab")
		)
		(fp_line
			(start -0.67945 0.3048)
			(end -0.120396 0.3048)
			(stroke
				(width 0.1)
				(type default)
			)
			(layer "B.Fab")
		)
		(fp_line
			(start -0.12065 -0.3048)
			(end -0.67945 -0.3048)
			(stroke
				(width 0.1)
				(type default)
			)
			(layer "B.Fab")
		)
		(fp_line
			(start -0.12065 -0.2794)
			(end -0.12065 -0.3048)
			(stroke
				(width 0.1)
				(type default)
			)
			(layer "B.Fab")
		)
		(fp_line
			(start -0.120396 0.2794)
			(end 0.12065 0.2794)
			(stroke
				(width 0.1)
				(type default)
			)
			(layer "B.Fab")
		)
		(fp_line
			(start -0.120396 0.3048)
			(end -0.120396 0.2794)
			(stroke
				(width 0.1)
				(type default)
			)
			(layer "B.Fab")
		)
		(fp_line
			(start 0.12065 -0.305054)
			(end 0.12065 -0.2794)
			(stroke
				(width 0.1)
				(type default)
			)
			(layer "B.Fab")
		)
		(fp_line
			(start 0.12065 -0.2794)
			(end -0.12065 -0.2794)
			(stroke
				(width 0.1)
				(type default)
			)
			(layer "B.Fab")
		)
		(fp_line
			(start 0.12065 0.2794)
			(end 0.12065 0.3048)
			(stroke
				(width 0.1)
				(type default)
			)
			(layer "B.Fab")
		)
		(fp_line
			(start 0.12065 0.3048)
			(end 0.67945 0.3048)
			(stroke
				(width 0.1)
				(type default)
			)
			(layer "B.Fab")
		)
		(fp_line
			(start 0.67945 -0.305054)
			(end 0.12065 -0.305054)
			(stroke
				(width 0.1)
				(type default)
			)
			(layer "B.Fab")
		)
		(fp_line
			(start 0.67945 0.3048)
			(end 0.67945 -0.305054)
			(stroke
				(width 0.1)
				(type default)
			)
			(layer "B.Fab")
		)
		(pad "1" smd circle
			(at 0.40005 0 180)
			(size 0 0)
			(layers "B.Cu" "B.Mask" "B.Paste")
			(net "P3V3_AUX_FPGA_VCCIO3")
		)
		(pad "2" smd circle
			(at -0.40005 0 180)
			(size 0 0)
			(layers "B.Cu" "B.Mask" "B.Paste")
			(net "GND")
		)
	)
	(footprint ""
		(layer "B.Cu")
		(at 232.692194 -129.673858 -90)
		(property "Reference" "C205"
			(at 0 0 90)
			(layer "B.SilkS")
			(hide yes)
			(effects
				(font
					(size 1.27 1.27)
				)
				(justify mirror)
			)
		)
		(property "Value" ""
			(at 0 0 90)
			(layer "B.Fab")
			(effects
				(font
					(size 1.27 1.27)
				)
				(justify mirror)
			)
		)
		(duplicate_pad_numbers_are_jumpers no)
		(fp_line
			(start -0.7874 0.4064)
			(end 0.7874 0.4064)
			(stroke
				(width 0.1524)
				(type default)
			)
			(layer "B.SilkS")
		)
		(fp_line
			(start 0.7874 0.4064)
			(end 0.7874 -0.4064)
			(stroke
				(width 0.1524)
				(type default)
			)
			(layer "B.SilkS")
		)
		(fp_line
			(start -0.7874 -0.4064)
			(end -0.7874 0.4064)
			(stroke
				(width 0.1524)
				(type default)
			)
			(layer "B.SilkS")
		)
		(fp_line
			(start 0.7874 -0.4064)
			(end -0.7874 -0.4064)
			(stroke
				(width 0.1524)
				(type default)
			)
			(layer "B.SilkS")
		)
		(fp_line
			(start -0.67945 0.3048)
			(end -0.120396 0.3048)
			(stroke
				(width 0.1)
				(type default)
			)
			(layer "B.Fab")
		)
		(fp_line
			(start -0.120396 0.3048)
			(end -0.120396 0.2794)
			(stroke
				(width 0.1)
				(type default)
			)
			(layer "B.Fab")
		)
		(fp_line
			(start 0.12065 0.3048)
			(end 0.67945 0.3048)
			(stroke
				(width 0.1)
				(type default)
			)
			(layer "B.Fab")
		)
		(fp_line
			(start 0.67945 0.3048)
			(end 0.67945 -0.305054)
			(stroke
				(width 0.1)
				(type default)
			)
			(layer "B.Fab")
		)
		(fp_line
			(start -0.120396 0.2794)
			(end 0.12065 0.2794)
			(stroke
				(width 0.1)
				(type default)
			)
			(layer "B.Fab")
		)
		(fp_line
			(start 0.12065 0.2794)
			(end 0.12065 0.3048)
			(stroke
				(width 0.1)
				(type default)
			)
			(layer "B.Fab")
		)
		(fp_line
			(start -0.12065 -0.2794)
			(end -0.12065 -0.3048)
			(stroke
				(width 0.1)
				(type default)
			)
			(layer "B.Fab")
		)
		(fp_line
			(start 0.12065 -0.2794)
			(end -0.12065 -0.2794)
			(stroke
				(width 0.1)
				(type default)
			)
			(layer "B.Fab")
		)
		(fp_line
			(start -0.67945 -0.3048)
			(end -0.67945 0.3048)
			(stroke
				(width 0.1)
				(type default)
			)
			(layer "B.Fab")
		)
		(fp_line
			(start -0.12065 -0.3048)
			(end -0.67945 -0.3048)
			(stroke
				(width 0.1)
				(type default)
			)
			(layer "B.Fab")
		)
		(fp_line
			(start 0.12065 -0.305054)
			(end 0.12065 -0.2794)
			(stroke
				(width 0.1)
				(type default)
			)
			(layer "B.Fab")
		)
		(fp_line
			(start 0.67945 -0.305054)
			(end 0.12065 -0.305054)
			(stroke
				(width 0.1)
				(type default)
			)
			(layer "B.Fab")
		)
		(pad "1" smd circle
			(at 0.40005 0 90)
			(size 0 0)
			(layers "B.Cu" "B.Mask" "B.Paste")
			(net "P3V3_DB2000_VDD")
		)
		(pad "2" smd circle
			(at -0.40005 0 90)
			(size 0 0)
			(layers "B.Cu" "B.Mask" "B.Paste")
			(net "GND")
		)
	)
)
